(kicad_pcb
	(version 20260206)
	(generator "pcbnew")
	(generator_version "10.0")
	(general
		(thickness 1.6)
		(legacy_teardrops no)
	)
	(paper "A4")
	(title_block
		(title "baseboard — 13948-1b.1110WZS1818.brd")
		(comment 1 "Honey Badger (Wiwynn) / footprints 1830-1837 of 2523")
	)
	(layers
		(0 "F.Cu" signal "TOP")
		(4 "In1.Cu" signal "L2GND")
		(6 "In2.Cu" signal "L3")
		(8 "In3.Cu" signal "L4VCC")
		(10 "In4.Cu" signal "L5VCC")
		(12 "In5.Cu" signal "L6")
		(14 "In6.Cu" signal "L7GND")
		(2 "B.Cu" signal "BOTTOM")
		(9 "F.Adhes" user "F.Adhesive")
		(11 "B.Adhes" user "B.Adhesive")
		(13 "F.Paste" user "Package Geometry/Pastemask Top")
		(15 "B.Paste" user "Package Geometry/Pastemask Bottom")
		(5 "F.SilkS" user "Ref Des/Silkscreen Top")
		(7 "B.SilkS" user "Ref Des/Silkscreen Bottom")
		(1 "F.Mask" user "Board Geometry/Soldermask Top")
		(3 "B.Mask" user "Board Geometry/Soldermask Bottom")
		(17 "Dwgs.User" user "User.Drawings")
		(19 "Cmts.User" user "User.Comments")
		(21 "Eco1.User" user "User.Eco1")
		(23 "Eco2.User" user "User.Eco2")
		(25 "Edge.Cuts" user "Board Geometry/Outline")
		(27 "Margin" user)
		(31 "F.CrtYd" user "Package Geometry/Place Bound Top")
		(29 "B.CrtYd" user "Package Geometry/Place Bound Bottom")
		(35 "F.Fab" user "Ref Des/Assembly Top")
		(33 "B.Fab" user "Ref Des/Assembly Bottom")
	)
	(footprint ""
		(layer "B.Cu")
		(at 91.19616 -34.417 90)
		(property "Reference" "SC938"
			(at 0 0 90)
			(layer "B.SilkS")
			(hide yes)
			(effects
				(font
					(size 1.27 1.27)
				)
				(justify mirror)
			)
		)
		(property "Value" "SCD1U6D3V1KX-GP"
			(at 2.8321 -1.7399 90)
			(unlocked yes)
			(layer "B.Fab")
			(hide yes)
			(effects
				(font
					(size 1.016 1.016)
					(thickness 0.1524)
				)
				(justify mirror)
			)
		)
		(property "Device Type" "C0201H13"
			(at 2.8321 -3.2639 90)
			(unlocked yes)
			(layer "B.Fab")
			(hide yes)
			(effects
				(font
					(size 1.016 1.016)
					(thickness 0.1524)
				)
				(justify mirror)
			)
		)
		(duplicate_pad_numbers_are_jumpers no)
		(fp_rect
			(start 0.2794 0.6477)
			(end -0.2794 -0.6477)
			(stroke
				(width 0)
				(type default)
			)
			(fill no)
			(layer "B.CrtYd")
		)
		(fp_rect
			(start 0.2794 0.6477)
			(end -0.2794 -0.6477)
			(stroke
				(width 0)
				(type default)
			)
			(fill no)
			(layer "B.Fab")
		)
		(pad "1" smd custom
			(at 0 -0.2794 270)
			(size 0.0762 0.0762)
			(layers "B.Cu" "B.Mask" "B.Paste")
			(net "SAS0_VDDH")
			(options
				(clearance outline)
				(anchor circle)
			)
			(primitives
				(gr_poly
					(pts
						(arc
							(start 0.1524 0.127)
							(mid 0.137521 0.162921)
							(end 0.1016 0.1778)
						)
						(arc
							(start -0.1016 0.1778)
							(mid -0.137521 0.162921)
							(end -0.1524 0.127)
						)
						(arc
							(start -0.1524 -0.127)
							(mid -0.137521 -0.162921)
							(end -0.1016 -0.1778)
						)
						(arc
							(start 0.1016 -0.1778)
							(mid 0.137521 -0.162921)
							(end 0.1524 -0.127)
						)
					)
					(width 0)
					(fill yes)
				)
			)
		)
		(pad "2" smd custom
			(at 0 0.2794 270)
			(size 0.0762 0.0762)
			(layers "B.Cu" "B.Mask" "B.Paste")
			(net "GND")
			(options
				(clearance outline)
				(anchor circle)
			)
			(primitives
				(gr_poly
					(pts
						(arc
							(start 0.1524 0.127)
							(mid 0.137521 0.162921)
							(end 0.1016 0.1778)
						)
						(arc
							(start -0.1016 0.1778)
							(mid -0.137521 0.162921)
							(end -0.1524 0.127)
						)
						(arc
							(start -0.1524 -0.127)
							(mid -0.137521 -0.162921)
							(end -0.1016 -0.1778)
						)
						(arc
							(start 0.1016 -0.1778)
							(mid 0.137521 -0.162921)
							(end 0.1524 -0.127)
						)
					)
					(width 0)
					(fill yes)
				)
			)
		)
	)
	(footprint ""
		(layer "B.Cu")
		(at 90.913966 -31.623 -90)
		(property "Reference" "SC959"
			(at 0 0 90)
			(layer "B.SilkS")
			(hide yes)
			(effects
				(font
					(size 1.27 1.27)
				)
				(justify mirror)
			)
		)
		(property "Value" "SCD1U6D3V1KX-GP"
			(at 2.8321 -1.7399 270)
			(unlocked yes)
			(layer "B.Fab")
			(hide yes)
			(effects
				(font
					(size 1.016 1.016)
					(thickness 0.1524)
				)
				(justify mirror)
			)
		)
		(property "Device Type" "C0201H13"
			(at 2.8321 -3.2639 270)
			(unlocked yes)
			(layer "B.Fab")
			(hide yes)
			(effects
				(font
					(size 1.016 1.016)
					(thickness 0.1524)
				)
				(justify mirror)
			)
		)
		(duplicate_pad_numbers_are_jumpers no)
		(fp_rect
			(start 0.2794 0.6477)
			(end -0.2794 -0.6477)
			(stroke
				(width 0)
				(type default)
			)
			(fill no)
			(layer "B.CrtYd")
		)
		(fp_rect
			(start 0.2794 0.6477)
			(end -0.2794 -0.6477)
			(stroke
				(width 0)
				(type default)
			)
			(fill no)
			(layer "B.Fab")
		)
		(pad "1" smd custom
			(at 0 -0.2794 90)
			(size 0.0762 0.0762)
			(layers "B.Cu" "B.Mask" "B.Paste")
			(net "SAS0_AVDD")
			(options
				(clearance outline)
				(anchor circle)
			)
			(primitives
				(gr_poly
					(pts
						(arc
							(start 0.1524 0.127)
							(mid 0.137521 0.162921)
							(end 0.1016 0.1778)
						)
						(arc
							(start -0.1016 0.1778)
							(mid -0.137521 0.162921)
							(end -0.1524 0.127)
						)
						(arc
							(start -0.1524 -0.127)
							(mid -0.137521 -0.162921)
							(end -0.1016 -0.1778)
						)
						(arc
							(start 0.1016 -0.1778)
							(mid 0.137521 -0.162921)
							(end 0.1524 -0.127)
						)
					)
					(width 0)
					(fill yes)
				)
			)
		)
		(pad "2" smd custom
			(at 0 0.2794 90)
			(size 0.0762 0.0762)
			(layers "B.Cu" "B.Mask" "B.Paste")
			(net "GND")
			(options
				(clearance outline)
				(anchor circle)
			)
			(primitives
				(gr_poly
					(pts
						(arc
							(start 0.1524 0.127)
							(mid 0.137521 0.162921)
							(end 0.1016 0.1778)
						)
						(arc
							(start -0.1016 0.1778)
							(mid -0.137521 0.162921)
							(end -0.1524 0.127)
						)
						(arc
							(start -0.1524 -0.127)
							(mid -0.137521 -0.162921)
							(end -0.1016 -0.1778)
						)
						(arc
							(start 0.1016 -0.1778)
							(mid 0.137521 -0.162921)
							(end 0.1524 -0.127)
						)
					)
					(width 0)
					(fill yes)
				)
			)
		)
	)
	(footprint ""
		(layer "B.Cu")
		(at 87.63 -100.584 90)
		(property "Reference" "SR825"
			(at 0 0 90)
			(layer "B.SilkS")
			(hide yes)
			(effects
				(font
					(size 1.27 1.27)
				)
				(justify mirror)
			)
		)
		(property "Value" "4K75R2F-1-GP"
			(at -0.064008 -3.993896 90)
			(unlocked yes)
			(layer "B.Fab")
			(hide yes)
			(effects
				(font
					(size 1.016 1.016)
					(thickness 0.1524)
				)
				(justify mirror)
			)
		)
		(property "Device Type" "R402H16"
			(at -0.064008 -5.517896 90)
			(unlocked yes)
			(layer "B.Fab")
			(hide yes)
			(effects
				(font
					(size 1.016 1.016)
					(thickness 0.1524)
				)
				(justify mirror)
			)
		)
		(duplicate_pad_numbers_are_jumpers no)
		(fp_line
			(start 0.508 -0.9398)
			(end 0.508 0.9398)
			(stroke
				(width 0.1524)
				(type default)
			)
			(layer "B.SilkS")
		)
		(fp_line
			(start -0.508 -0.9398)
			(end 0.508 -0.9398)
			(stroke
				(width 0.1524)
				(type default)
			)
			(layer "B.SilkS")
		)
		(fp_rect
			(start 0.508 0.9398)
			(end -0.508 -0.9398)
			(stroke
				(width 0)
				(type default)
			)
			(fill no)
			(layer "B.CrtYd")
		)
		(fp_rect
			(start 0.508 0.9398)
			(end -0.508 -0.9398)
			(stroke
				(width 0)
				(type default)
			)
			(fill no)
			(layer "B.Fab")
		)
		(pad "1" smd custom
			(at 0 -0.4445 270)
			(size 0.1397 0.1397)
			(layers "B.Cu" "B.Mask" "B.Paste")
			(net "P1V8_E")
			(options
				(clearance outline)
				(anchor circle)
			)
			(primitives
				(gr_poly
					(pts
						(arc
							(start -0.1778 0.2794)
							(mid -0.249642 0.249642)
							(end -0.2794 0.1778)
						)
						(arc
							(start -0.2794 -0.1778)
							(mid -0.249642 -0.249642)
							(end -0.1778 -0.2794)
						)
						(arc
							(start 0.1778 -0.2794)
							(mid 0.249642 -0.249642)
							(end 0.2794 -0.1778)
						)
						(arc
							(start 0.2794 0.1778)
							(mid 0.249642 0.249642)
							(end 0.1778 0.2794)
						)
					)
					(width 0)
					(fill yes)
				)
			)
		)
		(pad "2" smd custom
			(at 0 0.4445 270)
			(size 0.1397 0.1397)
			(layers "B.Cu" "B.Mask" "B.Paste")
			(net "EXP_FW_DET_BOARD_VER_1")
			(options
				(clearance outline)
				(anchor circle)
			)
			(primitives
				(gr_poly
					(pts
						(arc
							(start -0.1778 0.2794)
							(mid -0.249642 0.249642)
							(end -0.2794 0.1778)
						)
						(arc
							(start -0.2794 -0.1778)
							(mid -0.249642 -0.249642)
							(end -0.1778 -0.2794)
						)
						(arc
							(start 0.1778 -0.2794)
							(mid 0.249642 -0.249642)
							(end 0.2794 -0.1778)
						)
						(arc
							(start 0.2794 0.1778)
							(mid 0.249642 0.249642)
							(end 0.1778 0.2794)
						)
					)
					(width 0)
					(fill yes)
				)
			)
		)
	)
	(footprint ""
		(layer "B.Cu")
		(at 318.008 -171.577 -90)
		(property "Reference" "R466"
			(at 0 0 90)
			(layer "B.SilkS")
			(hide yes)
			(effects
				(font
					(size 1.27 1.27)
				)
				(justify mirror)
			)
		)
		(property "Value" "0R2J-2-GP"
			(at -0.064008 -3.993896 270)
			(unlocked yes)
			(layer "B.Fab")
			(hide yes)
			(effects
				(font
					(size 1.016 1.016)
					(thickness 0.1524)
				)
				(justify mirror)
			)
		)
		(property "Device Type" "R402H16"
			(at -0.064008 -5.517896 270)
			(unlocked yes)
			(layer "B.Fab")
			(hide yes)
			(effects
				(font
					(size 1.016 1.016)
					(thickness 0.1524)
				)
				(justify mirror)
			)
		)
		(duplicate_pad_numbers_are_jumpers no)
		(fp_line
			(start -0.508 -0.9398)
			(end 0.508 -0.9398)
			(stroke
				(width 0.1524)
				(type default)
			)
			(layer "B.SilkS")
		)
		(fp_line
			(start 0.508 -0.9398)
			(end 0.508 0.9398)
			(stroke
				(width 0.1524)
				(type default)
			)
			(layer "B.SilkS")
		)
		(fp_rect
			(start 0.508 0.9398)
			(end -0.508 -0.9398)
			(stroke
				(width 0)
				(type default)
			)
			(fill no)
			(layer "B.CrtYd")
		)
		(fp_rect
			(start 0.508 0.9398)
			(end -0.508 -0.9398)
			(stroke
				(width 0)
				(type default)
			)
			(fill no)
			(layer "B.Fab")
		)
		(pad "1" smd custom
			(at 0 -0.4445 90)
			(size 0.1397 0.1397)
			(layers "B.Cu" "B.Mask" "B.Paste")
			(net "BMC_I2C_F_SCL")
			(options
				(clearance outline)
				(anchor circle)
			)
			(primitives
				(gr_poly
					(pts
						(arc
							(start -0.1778 0.2794)
							(mid -0.249642 0.249642)
							(end -0.2794 0.1778)
						)
						(arc
							(start -0.2794 -0.1778)
							(mid -0.249642 -0.249642)
							(end -0.1778 -0.2794)
						)
						(arc
							(start 0.1778 -0.2794)
							(mid 0.249642 -0.249642)
							(end 0.2794 -0.1778)
						)
						(arc
							(start 0.2794 0.1778)
							(mid 0.249642 0.249642)
							(end 0.1778 0.2794)
						)
					)
					(width 0)
					(fill yes)
				)
			)
		)
		(pad "2" smd custom
			(at 0 0.4445 90)
			(size 0.1397 0.1397)
			(layers "B.Cu" "B.Mask" "B.Paste")
			(net "BMC0_SMB8_CLK")
			(options
				(clearance outline)
				(anchor circle)
			)
			(primitives
				(gr_poly
					(pts
						(arc
							(start -0.1778 0.2794)
							(mid -0.249642 0.249642)
							(end -0.2794 0.1778)
						)
						(arc
							(start -0.2794 -0.1778)
							(mid -0.249642 -0.249642)
							(end -0.1778 -0.2794)
						)
						(arc
							(start 0.1778 -0.2794)
							(mid 0.249642 -0.249642)
							(end 0.2794 -0.1778)
						)
						(arc
							(start 0.2794 0.1778)
							(mid 0.249642 0.249642)
							(end 0.1778 0.2794)
						)
					)
					(width 0)
					(fill yes)
				)
			)
		)
	)
	(footprint ""
		(layer "B.Cu")
		(at 290.449 -167.767)
		(property "Reference" "TP142"
			(at 0 0 0)
			(layer "B.SilkS")
			(hide yes)
			(effects
				(font
					(size 1.27 1.27)
				)
				(justify mirror)
			)
		)
		(property "Value" "TPAD28"
			(at -0.0127 -1.8034 0)
			(unlocked yes)
			(layer "B.Fab")
			(hide yes)
			(effects
				(font
					(size 1.016 1.016)
					(thickness 0.1524)
				)
				(justify mirror)
			)
		)
		(property "Device Type" "TPAD28"
			(at -0.0127 -3.3274 0)
			(unlocked yes)
			(layer "B.Fab")
			(hide yes)
			(effects
				(font
					(size 1.016 1.016)
					(thickness 0.1524)
				)
				(justify mirror)
			)
		)
		(duplicate_pad_numbers_are_jumpers no)
		(fp_poly
			(pts
				(arc
					(start 0.3556 0)
					(mid -0.3556 0)
					(end 0.3556 0)
				)
			)
			(stroke
				(width 0)
				(type default)
			)
			(fill no)
			(layer "B.CrtYd")
		)
		(fp_poly
			(pts
				(arc
					(start 0.6096 0)
					(mid -0.6096 0)
					(end 0.6096 0)
				)
			)
			(stroke
				(width 0)
				(type default)
			)
			(fill no)
			(layer "B.Fab")
		)
		(pad "1" smd circle
			(at 0 0 180)
			(size 0.7112 0.7112)
			(layers "B.Cu" "B.Mask" "B.Paste")
			(net "TP_BMC_GPIOE5")
		)
	)
	(footprint ""
		(layer "B.Cu")
		(at 116.47297 -94.615 90)
		(property "Reference" "SC1219"
			(at 0 0 90)
			(layer "B.SilkS")
			(hide yes)
			(effects
				(font
					(size 1.27 1.27)
				)
				(justify mirror)
			)
		)
		(property "Value" "SC1KP50V2KX-1GP"
			(at -1.1811 -2.7051 90)
			(unlocked yes)
			(layer "B.Fab")
			(hide yes)
			(effects
				(font
					(size 1.016 1.016)
					(thickness 0.1524)
				)
				(justify mirror)
			)
		)
		(property "Device Type" "C402H22"
			(at -1.1811 -4.2291 90)
			(unlocked yes)
			(layer "B.Fab")
			(hide yes)
			(effects
				(font
					(size 1.016 1.016)
					(thickness 0.1524)
				)
				(justify mirror)
			)
		)
		(duplicate_pad_numbers_are_jumpers no)
		(fp_rect
			(start 0.4318 0.9525)
			(end -0.4318 -0.9525)
			(stroke
				(width 0)
				(type default)
			)
			(fill no)
			(layer "B.CrtYd")
		)
		(fp_rect
			(start 0.4318 0.9525)
			(end -0.4318 -0.9525)
			(stroke
				(width 0)
				(type default)
			)
			(fill no)
			(layer "B.Fab")
		)
		(pad "1" smd custom
			(at 0 -0.4445 270)
			(size 0.1524 0.1524)
			(layers "B.Cu" "B.Mask" "B.Paste")
			(net "P0V9_E")
			(options
				(clearance outline)
				(anchor circle)
			)
			(primitives
				(gr_poly
					(pts
						(arc
							(start 0.3048 0.2032)
							(mid 0.275042 0.275042)
							(end 0.2032 0.3048)
						)
						(arc
							(start -0.2032 0.3048)
							(mid -0.275042 0.275042)
							(end -0.3048 0.2032)
						)
						(arc
							(start -0.3048 -0.2032)
							(mid -0.275042 -0.275042)
							(end -0.2032 -0.3048)
						)
						(arc
							(start 0.2032 -0.3048)
							(mid 0.275042 -0.275042)
							(end 0.3048 -0.2032)
						)
					)
					(width 0)
					(fill yes)
				)
			)
		)
		(pad "2" smd custom
			(at 0 0.4445 270)
			(size 0.1524 0.1524)
			(layers "B.Cu" "B.Mask" "B.Paste")
			(net "GND")
			(options
				(clearance outline)
				(anchor circle)
			)
			(primitives
				(gr_poly
					(pts
						(arc
							(start 0.3048 0.2032)
							(mid 0.275042 0.275042)
							(end 0.2032 0.3048)
						)
						(arc
							(start -0.2032 0.3048)
							(mid -0.275042 0.275042)
							(end -0.3048 0.2032)
						)
						(arc
							(start -0.3048 -0.2032)
							(mid -0.275042 -0.275042)
							(end -0.2032 -0.3048)
						)
						(arc
							(start 0.2032 -0.3048)
							(mid 0.275042 -0.275042)
							(end 0.3048 -0.2032)
						)
					)
					(width 0)
					(fill yes)
				)
			)
		)
	)
	(footprint ""
		(layer "B.Cu")
		(at 120.30837 -97.4852 90)
		(property "Reference" "SC1141"
			(at 0 0 90)
			(layer "B.SilkS")
			(hide yes)
			(effects
				(font
					(size 1.27 1.27)
				)
				(justify mirror)
			)
		)
		(property "Value" "SCD1U6D3V1KX-GP"
			(at 2.8321 -1.7399 90)
			(unlocked yes)
			(layer "B.Fab")
			(hide yes)
			(effects
				(font
					(size 1.016 1.016)
					(thickness 0.1524)
				)
				(justify mirror)
			)
		)
		(property "Device Type" "C0201H13"
			(at 2.8321 -3.2639 90)
			(unlocked yes)
			(layer "B.Fab")
			(hide yes)
			(effects
				(font
					(size 1.016 1.016)
					(thickness 0.1524)
				)
				(justify mirror)
			)
		)
		(duplicate_pad_numbers_are_jumpers no)
		(fp_rect
			(start 0.2794 0.6477)
			(end -0.2794 -0.6477)
			(stroke
				(width 0)
				(type default)
			)
			(fill no)
			(layer "B.CrtYd")
		)
		(fp_rect
			(start 0.2794 0.6477)
			(end -0.2794 -0.6477)
			(stroke
				(width 0)
				(type default)
			)
			(fill no)
			(layer "B.Fab")
		)
		(pad "1" smd custom
			(at 0 -0.2794 270)
			(size 0.0762 0.0762)
			(layers "B.Cu" "B.Mask" "B.Paste")
			(net "GB_VDDH2")
			(options
				(clearance outline)
				(anchor circle)
			)
			(primitives
				(gr_poly
					(pts
						(arc
							(start 0.1524 0.127)
							(mid 0.137521 0.162921)
							(end 0.1016 0.1778)
						)
						(arc
							(start -0.1016 0.1778)
							(mid -0.137521 0.162921)
							(end -0.1524 0.127)
						)
						(arc
							(start -0.1524 -0.127)
							(mid -0.137521 -0.162921)
							(end -0.1016 -0.1778)
						)
						(arc
							(start 0.1016 -0.1778)
							(mid 0.137521 -0.162921)
							(end 0.1524 -0.127)
						)
					)
					(width 0)
					(fill yes)
				)
			)
		)
		(pad "2" smd custom
			(at 0 0.2794 270)
			(size 0.0762 0.0762)
			(layers "B.Cu" "B.Mask" "B.Paste")
			(net "GND")
			(options
				(clearance outline)
				(anchor circle)
			)
			(primitives
				(gr_poly
					(pts
						(arc
							(start 0.1524 0.127)
							(mid 0.137521 0.162921)
							(end 0.1016 0.1778)
						)
						(arc
							(start -0.1016 0.1778)
							(mid -0.137521 0.162921)
							(end -0.1524 0.127)
						)
						(arc
							(start -0.1524 -0.127)
							(mid -0.137521 -0.162921)
							(end -0.1016 -0.1778)
						)
						(arc
							(start 0.1016 -0.1778)
							(mid 0.137521 -0.162921)
							(end 0.1524 -0.127)
						)
					)
					(width 0)
					(fill yes)
				)
			)
		)
	)
	(footprint ""
		(layer "B.Cu")
		(at 112.630966 -33.6296)
		(property "Reference" "STP138"
			(at 0 0 0)
			(layer "B.SilkS")
			(hide yes)
			(effects
				(font
					(size 1.27 1.27)
				)
				(justify mirror)
			)
		)
		(property "Value" "TPAD28"
			(at -0.0127 -1.8034 0)
			(unlocked yes)
			(layer "B.Fab")
			(hide yes)
			(effects
				(font
					(size 1.016 1.016)
					(thickness 0.1524)
				)
				(justify mirror)
			)
		)
		(property "Device Type" "TPAD28"
			(at -0.0127 -3.3274 0)
			(unlocked yes)
			(layer "B.Fab")
			(hide yes)
			(effects
				(font
					(size 1.016 1.016)
					(thickness 0.1524)
				)
				(justify mirror)
			)
		)
		(duplicate_pad_numbers_are_jumpers no)
		(fp_poly
			(pts
				(arc
					(start 0.3556 0)
					(mid -0.3556 0)
					(end 0.3556 0)
				)
			)
			(stroke
				(width 0)
				(type default)
			)
			(fill no)
			(layer "B.CrtYd")
		)
		(fp_poly
			(pts
				(arc
					(start 0.6096 0)
					(mid -0.6096 0)
					(end 0.6096 0)
				)
			)
			(stroke
				(width 0)
				(type default)
			)
			(fill no)
			(layer "B.Fab")
		)
		(pad "1" smd circle
			(at 0 0 180)
			(size 0.7112 0.7112)
			(layers "B.Cu" "B.Mask" "B.Paste")
			(net "IOC_GPIO_20")
		)
	)
)
